(kicad_pcb
	(version 20260206)
	(generator "pcbnew")
	(generator_version "10.0")
	(general
		(thickness 1.6)
		(legacy_teardrops no)
	)
	(paper "A4")
	(title_block
		(title "04192023_DAF0TMB3IC0_F0TG_MB_C_brd_V02_OCP.brd")
		(comment 1 "Grand Teton / footprints 2580-2586 of 8354")
	)
	(layers
		(0 "F.Cu" signal "TOP")
		(4 "In1.Cu" signal "GND")
		(6 "In2.Cu" signal "IN1")
		(8 "In3.Cu" signal "GND1")
		(10 "In4.Cu" signal "IN2")
		(12 "In5.Cu" signal "GND2")
		(14 "In6.Cu" signal "IN3")
		(16 "In7.Cu" signal "GND3")
		(18 "In8.Cu" signal "VCC")
		(20 "In9.Cu" signal "VCC1")
		(22 "In10.Cu" signal "GND4")
		(24 "In11.Cu" signal "IN4")
		(26 "In12.Cu" signal "GND5")
		(28 "In13.Cu" signal "IN5")
		(30 "In14.Cu" signal "GND6")
		(32 "In15.Cu" signal "IN6")
		(34 "In16.Cu" signal "GND7")
		(2 "B.Cu" signal "BOTTOM")
		(9 "F.Adhes" user "F.Adhesive")
		(11 "B.Adhes" user "B.Adhesive")
		(13 "F.Paste" user "Package Geometry/Pastemask Top")
		(15 "B.Paste" user "Package Geometry/Pastemask Bottom")
		(5 "F.SilkS" user "Ref Des/Silkscreen Top")
		(7 "B.SilkS" user "Ref Des/Silkscreen Bottom")
		(1 "F.Mask" user "Board Geometry/Soldermask Top")
		(3 "B.Mask" user "Board Geometry/Soldermask Bottom")
		(17 "Dwgs.User" user "User.Drawings")
		(19 "Cmts.User" user "User.Comments")
		(21 "Eco1.User" user "User.Eco1")
		(23 "Eco2.User" user "User.Eco2")
		(25 "Edge.Cuts" user "Board Geometry/Outline")
		(27 "Margin" user)
		(31 "F.CrtYd" user "Package Geometry/Place Bound Top")
		(29 "B.CrtYd" user "Package Geometry/Place Bound Bottom")
		(35 "F.Fab" user "Ref Des/Assembly Top")
		(33 "B.Fab" user "Ref Des/Assembly Bottom")
	)
	(footprint ""
		(layer "F.Cu")
		(at 442.828172 -33.062418 90)
		(property "Reference" "PR3835"
			(at 0 0 90)
			(layer "F.SilkS")
			(hide yes)
			(effects
				(font
					(size 1.27 1.27)
				)
			)
		)
		(property "Value" ""
			(at 0 0 90)
			(layer "F.Fab")
			(effects
				(font
					(size 1.27 1.27)
				)
			)
		)
		(duplicate_pad_numbers_are_jumpers no)
		(fp_line
			(start 0.7874 -0.4064)
			(end 0.7874 0.4064)
			(stroke
				(width 0.1524)
				(type default)
			)
			(layer "F.SilkS")
		)
		(fp_line
			(start -0.7874 -0.4064)
			(end 0.7874 -0.4064)
			(stroke
				(width 0.1524)
				(type default)
			)
			(layer "F.SilkS")
		)
		(fp_line
			(start 0.7874 0.4064)
			(end -0.7874 0.4064)
			(stroke
				(width 0.1524)
				(type default)
			)
			(layer "F.SilkS")
		)
		(fp_line
			(start -0.7874 0.4064)
			(end -0.7874 -0.4064)
			(stroke
				(width 0.1524)
				(type default)
			)
			(layer "F.SilkS")
		)
		(fp_line
			(start -0.12065 -0.305054)
			(end -0.12065 -0.2794)
			(stroke
				(width 0.1)
				(type default)
			)
			(layer "F.Fab")
		)
		(fp_line
			(start -0.67945 -0.305054)
			(end -0.12065 -0.305054)
			(stroke
				(width 0.1)
				(type default)
			)
			(layer "F.Fab")
		)
		(fp_line
			(start 0.67945 -0.3048)
			(end 0.67945 0.3048)
			(stroke
				(width 0.1)
				(type default)
			)
			(layer "F.Fab")
		)
		(fp_line
			(start 0.12065 -0.3048)
			(end 0.67945 -0.3048)
			(stroke
				(width 0.1)
				(type default)
			)
			(layer "F.Fab")
		)
		(fp_line
			(start 0.12065 -0.2794)
			(end 0.12065 -0.3048)
			(stroke
				(width 0.1)
				(type default)
			)
			(layer "F.Fab")
		)
		(fp_line
			(start -0.12065 -0.2794)
			(end 0.12065 -0.2794)
			(stroke
				(width 0.1)
				(type default)
			)
			(layer "F.Fab")
		)
		(fp_line
			(start 0.120396 0.2794)
			(end -0.12065 0.2794)
			(stroke
				(width 0.1)
				(type default)
			)
			(layer "F.Fab")
		)
		(fp_line
			(start -0.12065 0.2794)
			(end -0.12065 0.3048)
			(stroke
				(width 0.1)
				(type default)
			)
			(layer "F.Fab")
		)
		(fp_line
			(start 0.67945 0.3048)
			(end 0.120396 0.3048)
			(stroke
				(width 0.1)
				(type default)
			)
			(layer "F.Fab")
		)
		(fp_line
			(start 0.120396 0.3048)
			(end 0.120396 0.2794)
			(stroke
				(width 0.1)
				(type default)
			)
			(layer "F.Fab")
		)
		(fp_line
			(start -0.12065 0.3048)
			(end -0.67945 0.3048)
			(stroke
				(width 0.1)
				(type default)
			)
			(layer "F.Fab")
		)
		(fp_line
			(start -0.67945 0.3048)
			(end -0.67945 -0.305054)
			(stroke
				(width 0.1)
				(type default)
			)
			(layer "F.Fab")
		)
		(pad "1" smd circle
			(at -0.40005 0 90)
			(size 0 0)
			(layers "F.Cu" "F.Mask" "F.Paste")
			(net "P12V_OCP_ISET_1")
		)
		(pad "2" smd circle
			(at 0.40005 0 90)
			(size 0 0)
			(layers "F.Cu" "F.Mask" "F.Paste")
			(net "GND")
		)
	)
	(footprint ""
		(layer "F.Cu")
		(at 105.537 -421.005)
		(property "Reference" "R3461"
			(at 0 0 0)
			(layer "F.SilkS")
			(hide yes)
			(effects
				(font
					(size 1.27 1.27)
				)
			)
		)
		(property "Value" ""
			(at 0 0 0)
			(layer "F.Fab")
			(effects
				(font
					(size 1.27 1.27)
				)
			)
		)
		(duplicate_pad_numbers_are_jumpers no)
		(fp_line
			(start -0.7874 -0.4064)
			(end 0.7874 -0.4064)
			(stroke
				(width 0.1524)
				(type default)
			)
			(layer "F.SilkS")
		)
		(fp_line
			(start -0.7874 0.4064)
			(end -0.7874 -0.4064)
			(stroke
				(width 0.1524)
				(type default)
			)
			(layer "F.SilkS")
		)
		(fp_line
			(start 0.7874 -0.4064)
			(end 0.7874 0.4064)
			(stroke
				(width 0.1524)
				(type default)
			)
			(layer "F.SilkS")
		)
		(fp_line
			(start 0.7874 0.4064)
			(end -0.7874 0.4064)
			(stroke
				(width 0.1524)
				(type default)
			)
			(layer "F.SilkS")
		)
		(fp_line
			(start -0.67945 -0.305054)
			(end -0.12065 -0.305054)
			(stroke
				(width 0.1)
				(type default)
			)
			(layer "F.Fab")
		)
		(fp_line
			(start -0.67945 0.3048)
			(end -0.67945 -0.305054)
			(stroke
				(width 0.1)
				(type default)
			)
			(layer "F.Fab")
		)
		(fp_line
			(start -0.12065 -0.305054)
			(end -0.12065 -0.2794)
			(stroke
				(width 0.1)
				(type default)
			)
			(layer "F.Fab")
		)
		(fp_line
			(start -0.12065 -0.2794)
			(end 0.12065 -0.2794)
			(stroke
				(width 0.1)
				(type default)
			)
			(layer "F.Fab")
		)
		(fp_line
			(start -0.12065 0.2794)
			(end -0.12065 0.3048)
			(stroke
				(width 0.1)
				(type default)
			)
			(layer "F.Fab")
		)
		(fp_line
			(start -0.12065 0.3048)
			(end -0.67945 0.3048)
			(stroke
				(width 0.1)
				(type default)
			)
			(layer "F.Fab")
		)
		(fp_line
			(start 0.120396 0.2794)
			(end -0.12065 0.2794)
			(stroke
				(width 0.1)
				(type default)
			)
			(layer "F.Fab")
		)
		(fp_line
			(start 0.120396 0.3048)
			(end 0.120396 0.2794)
			(stroke
				(width 0.1)
				(type default)
			)
			(layer "F.Fab")
		)
		(fp_line
			(start 0.12065 -0.3048)
			(end 0.67945 -0.3048)
			(stroke
				(width 0.1)
				(type default)
			)
			(layer "F.Fab")
		)
		(fp_line
			(start 0.12065 -0.2794)
			(end 0.12065 -0.3048)
			(stroke
				(width 0.1)
				(type default)
			)
			(layer "F.Fab")
		)
		(fp_line
			(start 0.67945 -0.3048)
			(end 0.67945 0.3048)
			(stroke
				(width 0.1)
				(type default)
			)
			(layer "F.Fab")
		)
		(fp_line
			(start 0.67945 0.3048)
			(end 0.120396 0.3048)
			(stroke
				(width 0.1)
				(type default)
			)
			(layer "F.Fab")
		)
		(pad "1" smd circle
			(at -0.40005 0)
			(size 0 0)
			(layers "F.Cu" "F.Mask" "F.Paste")
			(net "P3V3_AUX")
		)
		(pad "2" smd circle
			(at 0.40005 0)
			(size 0 0)
			(layers "F.Cu" "F.Mask" "F.Paste")
			(net "GPU_NVS_PWR_BRAKE_N_R")
		)
	)
	(footprint ""
		(layer "F.Cu")
		(at 305.018948 -344.982038 90)
		(property "Reference" "PR509"
			(at 0 0 90)
			(layer "F.SilkS")
			(hide yes)
			(effects
				(font
					(size 1.27 1.27)
				)
			)
		)
		(property "Value" ""
			(at 0 0 90)
			(layer "F.Fab")
			(effects
				(font
					(size 1.27 1.27)
				)
			)
		)
		(duplicate_pad_numbers_are_jumpers no)
		(fp_line
			(start 0.7874 -0.4064)
			(end 0.7874 0.4064)
			(stroke
				(width 0.1524)
				(type default)
			)
			(layer "F.SilkS")
		)
		(fp_line
			(start -0.7874 -0.4064)
			(end 0.7874 -0.4064)
			(stroke
				(width 0.1524)
				(type default)
			)
			(layer "F.SilkS")
		)
		(fp_line
			(start 0.7874 0.4064)
			(end -0.7874 0.4064)
			(stroke
				(width 0.1524)
				(type default)
			)
			(layer "F.SilkS")
		)
		(fp_line
			(start -0.7874 0.4064)
			(end -0.7874 -0.4064)
			(stroke
				(width 0.1524)
				(type default)
			)
			(layer "F.SilkS")
		)
		(fp_line
			(start -0.12065 -0.305054)
			(end -0.12065 -0.2794)
			(stroke
				(width 0.1)
				(type default)
			)
			(layer "F.Fab")
		)
		(fp_line
			(start -0.67945 -0.305054)
			(end -0.12065 -0.305054)
			(stroke
				(width 0.1)
				(type default)
			)
			(layer "F.Fab")
		)
		(fp_line
			(start 0.67945 -0.3048)
			(end 0.67945 0.3048)
			(stroke
				(width 0.1)
				(type default)
			)
			(layer "F.Fab")
		)
		(fp_line
			(start 0.12065 -0.3048)
			(end 0.67945 -0.3048)
			(stroke
				(width 0.1)
				(type default)
			)
			(layer "F.Fab")
		)
		(fp_line
			(start 0.12065 -0.2794)
			(end 0.12065 -0.3048)
			(stroke
				(width 0.1)
				(type default)
			)
			(layer "F.Fab")
		)
		(fp_line
			(start -0.12065 -0.2794)
			(end 0.12065 -0.2794)
			(stroke
				(width 0.1)
				(type default)
			)
			(layer "F.Fab")
		)
		(fp_line
			(start 0.120396 0.2794)
			(end -0.12065 0.2794)
			(stroke
				(width 0.1)
				(type default)
			)
			(layer "F.Fab")
		)
		(fp_line
			(start -0.12065 0.2794)
			(end -0.12065 0.3048)
			(stroke
				(width 0.1)
				(type default)
			)
			(layer "F.Fab")
		)
		(fp_line
			(start 0.67945 0.3048)
			(end 0.120396 0.3048)
			(stroke
				(width 0.1)
				(type default)
			)
			(layer "F.Fab")
		)
		(fp_line
			(start 0.120396 0.3048)
			(end 0.120396 0.2794)
			(stroke
				(width 0.1)
				(type default)
			)
			(layer "F.Fab")
		)
		(fp_line
			(start -0.12065 0.3048)
			(end -0.67945 0.3048)
			(stroke
				(width 0.1)
				(type default)
			)
			(layer "F.Fab")
		)
		(fp_line
			(start -0.67945 0.3048)
			(end -0.67945 -0.305054)
			(stroke
				(width 0.1)
				(type default)
			)
			(layer "F.Fab")
		)
		(pad "1" smd circle
			(at -0.40005 0 90)
			(size 0 0)
			(layers "F.Cu" "F.Mask" "F.Paste")
			(net "SW_PVDDCR_CPU1_P0_SW4_RC")
		)
		(pad "2" smd circle
			(at 0.40005 0 90)
			(size 0 0)
			(layers "F.Cu" "F.Mask" "F.Paste")
			(net "GND")
		)
	)
	(footprint ""
		(layer "F.Cu")
		(at 197.180962 -39.046912)
		(property "Reference" "R1857"
			(at 0 0 0)
			(layer "F.SilkS")
			(hide yes)
			(effects
				(font
					(size 1.27 1.27)
				)
			)
		)
		(property "Value" ""
			(at 0 0 0)
			(layer "F.Fab")
			(effects
				(font
					(size 1.27 1.27)
				)
			)
		)
		(duplicate_pad_numbers_are_jumpers no)
		(fp_line
			(start -0.7874 -0.4064)
			(end 0.7874 -0.4064)
			(stroke
				(width 0.1524)
				(type default)
			)
			(layer "F.SilkS")
		)
		(fp_line
			(start -0.7874 0.4064)
			(end -0.7874 -0.4064)
			(stroke
				(width 0.1524)
				(type default)
			)
			(layer "F.SilkS")
		)
		(fp_line
			(start 0.7874 -0.4064)
			(end 0.7874 0.4064)
			(stroke
				(width 0.1524)
				(type default)
			)
			(layer "F.SilkS")
		)
		(fp_line
			(start 0.7874 0.4064)
			(end -0.7874 0.4064)
			(stroke
				(width 0.1524)
				(type default)
			)
			(layer "F.SilkS")
		)
		(fp_line
			(start -0.67945 -0.305054)
			(end -0.12065 -0.305054)
			(stroke
				(width 0.1)
				(type default)
			)
			(layer "F.Fab")
		)
		(fp_line
			(start -0.67945 0.3048)
			(end -0.67945 -0.305054)
			(stroke
				(width 0.1)
				(type default)
			)
			(layer "F.Fab")
		)
		(fp_line
			(start -0.12065 -0.305054)
			(end -0.12065 -0.2794)
			(stroke
				(width 0.1)
				(type default)
			)
			(layer "F.Fab")
		)
		(fp_line
			(start -0.12065 -0.2794)
			(end 0.12065 -0.2794)
			(stroke
				(width 0.1)
				(type default)
			)
			(layer "F.Fab")
		)
		(fp_line
			(start -0.12065 0.2794)
			(end -0.12065 0.3048)
			(stroke
				(width 0.1)
				(type default)
			)
			(layer "F.Fab")
		)
		(fp_line
			(start -0.12065 0.3048)
			(end -0.67945 0.3048)
			(stroke
				(width 0.1)
				(type default)
			)
			(layer "F.Fab")
		)
		(fp_line
			(start 0.120396 0.2794)
			(end -0.12065 0.2794)
			(stroke
				(width 0.1)
				(type default)
			)
			(layer "F.Fab")
		)
		(fp_line
			(start 0.120396 0.3048)
			(end 0.120396 0.2794)
			(stroke
				(width 0.1)
				(type default)
			)
			(layer "F.Fab")
		)
		(fp_line
			(start 0.12065 -0.3048)
			(end 0.67945 -0.3048)
			(stroke
				(width 0.1)
				(type default)
			)
			(layer "F.Fab")
		)
		(fp_line
			(start 0.12065 -0.2794)
			(end 0.12065 -0.3048)
			(stroke
				(width 0.1)
				(type default)
			)
			(layer "F.Fab")
		)
		(fp_line
			(start 0.67945 -0.3048)
			(end 0.67945 0.3048)
			(stroke
				(width 0.1)
				(type default)
			)
			(layer "F.Fab")
		)
		(fp_line
			(start 0.67945 0.3048)
			(end 0.120396 0.3048)
			(stroke
				(width 0.1)
				(type default)
			)
			(layer "F.Fab")
		)
		(pad "1" smd circle
			(at -0.40005 0)
			(size 0 0)
			(layers "F.Cu" "F.Mask" "F.Paste")
			(net "P3V3_AUX")
		)
		(pad "2" smd circle
			(at 0.40005 0)
			(size 0 0)
			(layers "F.Cu" "F.Mask" "F.Paste")
			(net "P12V_SCM_EN")
		)
	)
	(footprint ""
		(layer "F.Cu")
		(at 403.682962 -60.7695 180)
		(property "Reference" "R477"
			(at 0 0 180)
			(layer "F.SilkS")
			(hide yes)
			(effects
				(font
					(size 1.27 1.27)
				)
			)
		)
		(property "Value" ""
			(at 0 0 180)
			(layer "F.Fab")
			(effects
				(font
					(size 1.27 1.27)
				)
			)
		)
		(duplicate_pad_numbers_are_jumpers no)
		(fp_line
			(start 0.7874 0.4064)
			(end -0.7874 0.4064)
			(stroke
				(width 0.1524)
				(type default)
			)
			(layer "F.SilkS")
		)
		(fp_line
			(start 0.7874 -0.4064)
			(end 0.7874 0.4064)
			(stroke
				(width 0.1524)
				(type default)
			)
			(layer "F.SilkS")
		)
		(fp_line
			(start -0.7874 0.4064)
			(end -0.7874 -0.4064)
			(stroke
				(width 0.1524)
				(type default)
			)
			(layer "F.SilkS")
		)
		(fp_line
			(start -0.7874 -0.4064)
			(end 0.7874 -0.4064)
			(stroke
				(width 0.1524)
				(type default)
			)
			(layer "F.SilkS")
		)
		(fp_line
			(start 0.67945 0.3048)
			(end 0.120396 0.3048)
			(stroke
				(width 0.1)
				(type default)
			)
			(layer "F.Fab")
		)
		(fp_line
			(start 0.67945 -0.3048)
			(end 0.67945 0.3048)
			(stroke
				(width 0.1)
				(type default)
			)
			(layer "F.Fab")
		)
		(fp_line
			(start 0.12065 -0.2794)
			(end 0.12065 -0.3048)
			(stroke
				(width 0.1)
				(type default)
			)
			(layer "F.Fab")
		)
		(fp_line
			(start 0.12065 -0.3048)
			(end 0.67945 -0.3048)
			(stroke
				(width 0.1)
				(type default)
			)
			(layer "F.Fab")
		)
		(fp_line
			(start 0.120396 0.3048)
			(end 0.120396 0.2794)
			(stroke
				(width 0.1)
				(type default)
			)
			(layer "F.Fab")
		)
		(fp_line
			(start 0.120396 0.2794)
			(end -0.12065 0.2794)
			(stroke
				(width 0.1)
				(type default)
			)
			(layer "F.Fab")
		)
		(fp_line
			(start -0.12065 0.3048)
			(end -0.67945 0.3048)
			(stroke
				(width 0.1)
				(type default)
			)
			(layer "F.Fab")
		)
		(fp_line
			(start -0.12065 0.2794)
			(end -0.12065 0.3048)
			(stroke
				(width 0.1)
				(type default)
			)
			(layer "F.Fab")
		)
		(fp_line
			(start -0.12065 -0.2794)
			(end 0.12065 -0.2794)
			(stroke
				(width 0.1)
				(type default)
			)
			(layer "F.Fab")
		)
		(fp_line
			(start -0.12065 -0.305054)
			(end -0.12065 -0.2794)
			(stroke
				(width 0.1)
				(type default)
			)
			(layer "F.Fab")
		)
		(fp_line
			(start -0.67945 0.3048)
			(end -0.67945 -0.305054)
			(stroke
				(width 0.1)
				(type default)
			)
			(layer "F.Fab")
		)
		(fp_line
			(start -0.67945 -0.305054)
			(end -0.12065 -0.305054)
			(stroke
				(width 0.1)
				(type default)
			)
			(layer "F.Fab")
		)
		(pad "1" smd circle
			(at -0.40005 0 180)
			(size 0 0)
			(layers "F.Cu" "F.Mask" "F.Paste")
			(net "CPU0_XTRIG_L7")
		)
		(pad "2" smd circle
			(at 0.40005 0 180)
			(size 0 0)
			(layers "F.Cu" "F.Mask" "F.Paste")
			(net "HDT_CPU0_XTRIG_L7")
		)
	)
	(footprint ""
		(layer "F.Cu")
		(at 39.842694 -422.06037)
		(property "Reference" "R6154"
			(at 0 0 0)
			(layer "F.SilkS")
			(hide yes)
			(effects
				(font
					(size 1.27 1.27)
				)
			)
		)
		(property "Value" ""
			(at 0 0 0)
			(layer "F.Fab")
			(effects
				(font
					(size 1.27 1.27)
				)
			)
		)
		(duplicate_pad_numbers_are_jumpers no)
		(fp_line
			(start -0.32512 -0.175006)
			(end 0.32512 -0.175006)
			(stroke
				(width 0.1)
				(type default)
			)
			(layer "F.Fab")
		)
		(fp_line
			(start -0.32512 0.175006)
			(end -0.32512 -0.175006)
			(stroke
				(width 0.1)
				(type default)
			)
			(layer "F.Fab")
		)
		(fp_line
			(start 0.32512 -0.175006)
			(end 0.32512 0.175006)
			(stroke
				(width 0.1)
				(type default)
			)
			(layer "F.Fab")
		)
		(fp_line
			(start 0.32512 0.175006)
			(end -0.32512 0.175006)
			(stroke
				(width 0.1)
				(type default)
			)
			(layer "F.Fab")
		)
		(pad "1" smd rect
			(at -0.2667 0)
			(size 0.3048 0.381)
			(layers "F.Cu" "F.Mask" "F.Paste")
			(net "P2E_MB_BMC_TX_C_DP<0>")
		)
		(pad "2" smd rect
			(at 0.2667 0 180)
			(size 0.3048 0.381)
			(layers "F.Cu" "F.Mask" "F.Paste")
			(net "P2E_MB_BMC_TX_C_R2_DP<0>")
		)
	)
	(footprint ""
		(layer "F.Cu")
		(at 87.54618 -58.21172 180)
		(property "Reference" "R3826"
			(at 0 0 180)
			(layer "F.SilkS")
			(hide yes)
			(effects
				(font
					(size 1.27 1.27)
				)
			)
		)
		(property "Value" ""
			(at 0 0 180)
			(layer "F.Fab")
			(effects
				(font
					(size 1.27 1.27)
				)
			)
		)
		(duplicate_pad_numbers_are_jumpers no)
		(fp_line
			(start 0.7874 0.4064)
			(end -0.7874 0.4064)
			(stroke
				(width 0.1524)
				(type default)
			)
			(layer "F.SilkS")
		)
		(fp_line
			(start 0.7874 -0.4064)
			(end 0.7874 0.4064)
			(stroke
				(width 0.1524)
				(type default)
			)
			(layer "F.SilkS")
		)
		(fp_line
			(start -0.7874 0.4064)
			(end -0.7874 -0.4064)
			(stroke
				(width 0.1524)
				(type default)
			)
			(layer "F.SilkS")
		)
		(fp_line
			(start -0.7874 -0.4064)
			(end 0.7874 -0.4064)
			(stroke
				(width 0.1524)
				(type default)
			)
			(layer "F.SilkS")
		)
		(fp_line
			(start 0.67945 0.3048)
			(end 0.120396 0.3048)
			(stroke
				(width 0.1)
				(type default)
			)
			(layer "F.Fab")
		)
		(fp_line
			(start 0.67945 -0.3048)
			(end 0.67945 0.3048)
			(stroke
				(width 0.1)
				(type default)
			)
			(layer "F.Fab")
		)
		(fp_line
			(start 0.12065 -0.2794)
			(end 0.12065 -0.3048)
			(stroke
				(width 0.1)
				(type default)
			)
			(layer "F.Fab")
		)
		(fp_line
			(start 0.12065 -0.3048)
			(end 0.67945 -0.3048)
			(stroke
				(width 0.1)
				(type default)
			)
			(layer "F.Fab")
		)
		(fp_line
			(start 0.120396 0.3048)
			(end 0.120396 0.2794)
			(stroke
				(width 0.1)
				(type default)
			)
			(layer "F.Fab")
		)
		(fp_line
			(start 0.120396 0.2794)
			(end -0.12065 0.2794)
			(stroke
				(width 0.1)
				(type default)
			)
			(layer "F.Fab")
		)
		(fp_line
			(start -0.12065 0.3048)
			(end -0.67945 0.3048)
			(stroke
				(width 0.1)
				(type default)
			)
			(layer "F.Fab")
		)
		(fp_line
			(start -0.12065 0.2794)
			(end -0.12065 0.3048)
			(stroke
				(width 0.1)
				(type default)
			)
			(layer "F.Fab")
		)
		(fp_line
			(start -0.12065 -0.2794)
			(end 0.12065 -0.2794)
			(stroke
				(width 0.1)
				(type default)
			)
			(layer "F.Fab")
		)
		(fp_line
			(start -0.12065 -0.305054)
			(end -0.12065 -0.2794)
			(stroke
				(width 0.1)
				(type default)
			)
			(layer "F.Fab")
		)
		(fp_line
			(start -0.67945 0.3048)
			(end -0.67945 -0.305054)
			(stroke
				(width 0.1)
				(type default)
			)
			(layer "F.Fab")
		)
		(fp_line
			(start -0.67945 -0.305054)
			(end -0.12065 -0.305054)
			(stroke
				(width 0.1)
				(type default)
			)
			(layer "F.Fab")
		)
		(pad "1" smd circle
			(at -0.40005 0 180)
			(size 0 0)
			(layers "F.Cu" "F.Mask" "F.Paste")
			(net "P3V3_AUX")
		)
		(pad "2" smd circle
			(at 0.40005 0 180)
			(size 0 0)
			(layers "F.Cu" "F.Mask" "F.Paste")
			(net "OCP_V3_2_P3V3_PWRGD")
		)
	)
)
